# T6G (Grand Teton) — schematic netlist excerpt (pin names and nets, part order shuffled) for the footprints in the layout excerpt that follows; sources: Cadence DE-HDL packaged netlist, KiCad conversion of 04192023_DAF0TMB3IC0_F0TG_MB_C_brd_V02_OCP.brd

R9018  Q_RES  0 5% CHIP  pkg 0402LF  page 245 : A = PRSNT_CABLE_GPU_A3_ISO_N ; B = PRSNT_CABLE_GPU_A3_ISO_R_N
R3825  Q_RES  100K 1% CHIP  pkg 0402LF  page 140 : A = P3V3_AUX ; B = HP_LVC3_OCP_V3_2_P12V_PWRGD

(kicad_pcb
	(version 20260206)
	(generator "pcbnew")
	(generator_version "10.0")
	(general
		(thickness 1.6)
		(legacy_teardrops no)
	)
	(paper "A4")
	(title_block
		(title "04192023_DAF0TMB3IC0_F0TG_MB_C_brd_V02_OCP.brd")
		(comment 1 "Grand Teton / footprints 2592-2593 of 8354")
	)
	(layers
		(0 "F.Cu" signal "TOP")
		(4 "In1.Cu" signal "GND")
		(6 "In2.Cu" signal "IN1")
		(8 "In3.Cu" signal "GND1")
		(10 "In4.Cu" signal "IN2")
		(12 "In5.Cu" signal "GND2")
		(14 "In6.Cu" signal "IN3")
		(16 "In7.Cu" signal "GND3")
		(18 "In8.Cu" signal "VCC")
		(20 "In9.Cu" signal "VCC1")
		(22 "In10.Cu" signal "GND4")
		(24 "In11.Cu" signal "IN4")
		(26 "In12.Cu" signal "GND5")
		(28 "In13.Cu" signal "IN5")
		(30 "In14.Cu" signal "GND6")
		(32 "In15.Cu" signal "IN6")
		(34 "In16.Cu" signal "GND7")
		(2 "B.Cu" signal "BOTTOM")
		(9 "F.Adhes" user "F.Adhesive")
		(11 "B.Adhes" user "B.Adhesive")
		(13 "F.Paste" user "Package Geometry/Pastemask Top")
		(15 "B.Paste" user "Package Geometry/Pastemask Bottom")
		(5 "F.SilkS" user "Ref Des/Silkscreen Top")
		(7 "B.SilkS" user "Ref Des/Silkscreen Bottom")
		(1 "F.Mask" user "Board Geometry/Soldermask Top")
		(3 "B.Mask" user "Board Geometry/Soldermask Bottom")
		(17 "Dwgs.User" user "User.Drawings")
		(19 "Cmts.User" user "User.Comments")
		(21 "Eco1.User" user "User.Eco1")
		(23 "Eco2.User" user "User.Eco2")
		(25 "Edge.Cuts" user "Board Geometry/Outline")
		(27 "Margin" user)
		(31 "F.CrtYd" user "Package Geometry/Place Bound Top")
		(29 "B.CrtYd" user "Package Geometry/Place Bound Bottom")
		(35 "F.Fab" user "Ref Des/Assembly Top")
		(33 "B.Fab" user "Ref Des/Assembly Bottom")
	)
	(footprint ""
		(layer "F.Cu")
		(at 181.688486 -426.349922 -90)
		(property "Reference" "R9018"
			(at 0 0 270)
			(layer "F.SilkS")
			(hide yes)
			(effects
				(font
					(size 1.27 1.27)
				)
			)
		)
		(property "Value" ""
			(at 0 0 270)
			(layer "F.Fab")
			(effects
				(font
					(size 1.27 1.27)
				)
			)
		)
		(duplicate_pad_numbers_are_jumpers no)
		(fp_line
			(start -0.7874 0.4064)
			(end -0.7874 -0.4064)
			(stroke
				(width 0.1524)
				(type default)
			)
			(layer "F.SilkS")
		)
		(fp_line
			(start 0.7874 0.4064)
			(end -0.7874 0.4064)
			(stroke
				(width 0.1524)
				(type default)
			)
			(layer "F.SilkS")
		)
		(fp_line
			(start -0.7874 -0.4064)
			(end 0.7874 -0.4064)
			(stroke
				(width 0.1524)
				(type default)
			)
			(layer "F.SilkS")
		)
		(fp_line
			(start 0.7874 -0.4064)
			(end 0.7874 0.4064)
			(stroke
				(width 0.1524)
				(type default)
			)
			(layer "F.SilkS")
		)
		(fp_line
			(start -0.67945 0.3048)
			(end -0.67945 -0.305054)
			(stroke
				(width 0.1)
				(type default)
			)
			(layer "F.Fab")
		)
		(fp_line
			(start -0.12065 0.3048)
			(end -0.67945 0.3048)
			(stroke
				(width 0.1)
				(type default)
			)
			(layer "F.Fab")
		)
		(fp_line
			(start 0.120396 0.3048)
			(end 0.120396 0.2794)
			(stroke
				(width 0.1)
				(type default)
			)
			(layer "F.Fab")
		)
		(fp_line
			(start 0.67945 0.3048)
			(end 0.120396 0.3048)
			(stroke
				(width 0.1)
				(type default)
			)
			(layer "F.Fab")
		)
		(fp_line
			(start -0.12065 0.2794)
			(end -0.12065 0.3048)
			(stroke
				(width 0.1)
				(type default)
			)
			(layer "F.Fab")
		)
		(fp_line
			(start 0.120396 0.2794)
			(end -0.12065 0.2794)
			(stroke
				(width 0.1)
				(type default)
			)
			(layer "F.Fab")
		)
		(fp_line
			(start -0.12065 -0.2794)
			(end 0.12065 -0.2794)
			(stroke
				(width 0.1)
				(type default)
			)
			(layer "F.Fab")
		)
		(fp_line
			(start 0.12065 -0.2794)
			(end 0.12065 -0.3048)
			(stroke
				(width 0.1)
				(type default)
			)
			(layer "F.Fab")
		)
		(fp_line
			(start 0.12065 -0.3048)
			(end 0.67945 -0.3048)
			(stroke
				(width 0.1)
				(type default)
			)
			(layer "F.Fab")
		)
		(fp_line
			(start 0.67945 -0.3048)
			(end 0.67945 0.3048)
			(stroke
				(width 0.1)
				(type default)
			)
			(layer "F.Fab")
		)
		(fp_line
			(start -0.67945 -0.305054)
			(end -0.12065 -0.305054)
			(stroke
				(width 0.1)
				(type default)
			)
			(layer "F.Fab")
		)
		(fp_line
			(start -0.12065 -0.305054)
			(end -0.12065 -0.2794)
			(stroke
				(width 0.1)
				(type default)
			)
			(layer "F.Fab")
		)
		(pad "1" smd circle
			(at -0.40005 0 270)
			(size 0 0)
			(layers "F.Cu" "F.Mask" "F.Paste")
			(net "PRSNT_CABLE_GPU_A3_ISO_N")
		)
		(pad "2" smd circle
			(at 0.40005 0 270)
			(size 0 0)
			(layers "F.Cu" "F.Mask" "F.Paste")
			(net "PRSNT_CABLE_GPU_A3_ISO_R_N")
		)
	)
	(footprint ""
		(layer "F.Cu")
		(at 82.706718 -19.142202 -90)
		(property "Reference" "R3825"
			(at 0 0 270)
			(layer "F.SilkS")
			(hide yes)
			(effects
				(font
					(size 1.27 1.27)
				)
			)
		)
		(property "Value" ""
			(at 0 0 270)
			(layer "F.Fab")
			(effects
				(font
					(size 1.27 1.27)
				)
			)
		)
		(duplicate_pad_numbers_are_jumpers no)
		(fp_line
			(start -0.7874 0.4064)
			(end -0.7874 -0.4064)
			(stroke
				(width 0.1524)
				(type default)
			)
			(layer "F.SilkS")
		)
		(fp_line
			(start 0.7874 0.4064)
			(end -0.7874 0.4064)
			(stroke
				(width 0.1524)
				(type default)
			)
			(layer "F.SilkS")
		)
		(fp_line
			(start -0.7874 -0.4064)
			(end 0.7874 -0.4064)
			(stroke
				(width 0.1524)
				(type default)
			)
			(layer "F.SilkS")
		)
		(fp_line
			(start 0.7874 -0.4064)
			(end 0.7874 0.4064)
			(stroke
				(width 0.1524)
				(type default)
			)
			(layer "F.SilkS")
		)
		(fp_line
			(start -0.67945 0.3048)
			(end -0.67945 -0.305054)
			(stroke
				(width 0.1)
				(type default)
			)
			(layer "F.Fab")
		)
		(fp_line
			(start -0.12065 0.3048)
			(end -0.67945 0.3048)
			(stroke
				(width 0.1)
				(type default)
			)
			(layer "F.Fab")
		)
		(fp_line
			(start 0.120396 0.3048)
			(end 0.120396 0.2794)
			(stroke
				(width 0.1)
				(type default)
			)
			(layer "F.Fab")
		)
		(fp_line
			(start 0.67945 0.3048)
			(end 0.120396 0.3048)
			(stroke
				(width 0.1)
				(type default)
			)
			(layer "F.Fab")
		)
		(fp_line
			(start -0.12065 0.2794)
			(end -0.12065 0.3048)
			(stroke
				(width 0.1)
				(type default)
			)
			(layer "F.Fab")
		)
		(fp_line
			(start 0.120396 0.2794)
			(end -0.12065 0.2794)
			(stroke
				(width 0.1)
				(type default)
			)
			(layer "F.Fab")
		)
		(fp_line
			(start -0.12065 -0.2794)
			(end 0.12065 -0.2794)
			(stroke
				(width 0.1)
				(type default)
			)
			(layer "F.Fab")
		)
		(fp_line
			(start 0.12065 -0.2794)
			(end 0.12065 -0.3048)
			(stroke
				(width 0.1)
				(type default)
			)
			(layer "F.Fab")
		)
		(fp_line
			(start 0.12065 -0.3048)
			(end 0.67945 -0.3048)
			(stroke
				(width 0.1)
				(type default)
			)
			(layer "F.Fab")
		)
		(fp_line
			(start 0.67945 -0.3048)
			(end 0.67945 0.3048)
			(stroke
				(width 0.1)
				(type default)
			)
			(layer "F.Fab")
		)
		(fp_line
			(start -0.67945 -0.305054)
			(end -0.12065 -0.305054)
			(stroke
				(width 0.1)
				(type default)
			)
			(layer "F.Fab")
		)
		(fp_line
			(start -0.12065 -0.305054)
			(end -0.12065 -0.2794)
			(stroke
				(width 0.1)
				(type default)
			)
			(layer "F.Fab")
		)
		(pad "1" smd circle
			(at -0.40005 0 270)
			(size 0 0)
			(layers "F.Cu" "F.Mask" "F.Paste")
			(net "P3V3_AUX")
		)
		(pad "2" smd circle
			(at 0.40005 0 270)
			(size 0 0)
			(layers "F.Cu" "F.Mask" "F.Paste")
			(net "HP_LVC3_OCP_V3_2_P12V_PWRGD")
		)
	)
)
